G04 ================== begin FILE IDENTIFICATION RECORD ==================*
G04 Layout Name:  15669-1.brd*
G04 Film Name:    SE_REF_L8*
G04 File Format:  Gerber RS274X*
G04 File Origin:  Cadence Allegro 16.5-S056*
G04 Origin Date:  Wed Nov 16 04:09:34 2016*
G04 *
G04 Layer:  BOARD GEOMETRY/SE_REF_L8_TBL*
G04 Layer:  BOARD GEOMETRY/SE_REF_L8_BOTTOM*
G04 Layer:  BOARD GEOMETRY/PANEL_OUTLINE*
G04 *
G04 Offset:    (0.00 0.00)*
G04 Mirror:    No*
G04 Mode:      Positive*
G04 Rotation:  0*
G04 FullContactRelief:  No*
G04 UndefLineWidth:     6.00*
G04 ================== end FILE IDENTIFICATION RECORD ====================*
%FSLAX35Y35*MOIN*%
%IR0*IPPOS*OFA0.00000B0.00000*MIA0B0*SFA1.00000B1.00000*%
%ADD10C,.02*%
%ADD11C,.006*%
%ADD12C,.00675*%
G75*
%LPD*%
G75*
G54D10*
G01X1178253Y1923126D02*
X1895753D01*
G01X1178253Y1888476D02*
X1895753D01*
G01X1178253Y1957776D02*
Y1888476D01*
G01Y1957776D02*
X1895753D01*
G01X1353253D02*
Y1888476D01*
G01X1580753Y1957776D02*
Y1888476D01*
G01X1685753Y1957776D02*
Y1888476D01*
G01X1895753Y1957776D02*
Y1888476D01*
G54D11*
G01X-84302Y-32800D02*
Y-50300D01*
G01X-89324Y-32800D02*
X-79280D01*
G01X-70514Y-50300D02*
Y-32800D01*
G01Y-41258D02*
X-69422Y-39800D01*
X-68330Y-38925D01*
X-66584Y-38634D01*
X-65274Y-38925D01*
X-63745Y-40092D01*
X-63090Y-41842D01*
Y-50300D01*
G01X-49302Y-38634D02*
Y-50300D01*
G01Y-33967D02*
X-49739Y-33675D01*
Y-33092D01*
X-49302Y-32800D01*
X-48865Y-33092D01*
Y-33675D01*
X-49302Y-33967D01*
G01X-35077Y-48259D02*
X-33985Y-49425D01*
X-32457Y-50300D01*
X-31147D01*
X-29837Y-49717D01*
X-28964Y-48842D01*
X-28527Y-47676D01*
X-28745Y-45925D01*
X-29619Y-45050D01*
X-33549Y-43300D01*
X-34422Y-41258D01*
X-33985Y-39800D01*
X-33112Y-38925D01*
X-31802Y-38634D01*
X-30492Y-38925D01*
X-29182Y-39800D01*
G01X141Y-54675D02*
X1670Y-55842D01*
X3416Y-56133D01*
X4944Y-55842D01*
X6255Y-54384D01*
X7128Y-52342D01*
Y-38634D01*
G01Y-40967D02*
X6255Y-39800D01*
X4944Y-38925D01*
X3416Y-38634D01*
X1670Y-39217D01*
X578Y-40383D01*
X-296Y-42425D01*
X-732Y-44467D01*
X-514Y-46217D01*
X360Y-48259D01*
X1670Y-49717D01*
X3416Y-50300D01*
X4726Y-50008D01*
X6255Y-48842D01*
X7128Y-47676D01*
G01X17423Y-42425D02*
X24410D01*
X23755Y-40383D01*
X22663Y-39217D01*
X21135Y-38634D01*
X19606Y-38925D01*
X18296Y-39800D01*
X17423Y-41842D01*
X16986Y-43592D01*
Y-45342D01*
X17423Y-47092D01*
X18515Y-48842D01*
X19825Y-50008D01*
X21353Y-50300D01*
X22881Y-49717D01*
X24410Y-47967D01*
G01X35141Y-50300D02*
Y-38634D01*
G01Y-40967D02*
X36233Y-39800D01*
X37325Y-38925D01*
X38853Y-38634D01*
X39944Y-38925D01*
X41255Y-39800D01*
G01X51768Y-50300D02*
Y-32800D01*
G01Y-41550D02*
X52860Y-39800D01*
X54170Y-38925D01*
X55480Y-38634D01*
X57444Y-39217D01*
X58755Y-40383D01*
X59628Y-42425D01*
Y-44758D01*
X59191Y-47092D01*
X58318Y-48842D01*
X56790Y-50008D01*
X55480Y-50300D01*
X54170Y-50008D01*
X52860Y-49134D01*
X51768Y-47676D01*
G01X69923Y-42425D02*
X76910D01*
X76255Y-40383D01*
X75163Y-39217D01*
X73635Y-38634D01*
X72106Y-38925D01*
X70796Y-39800D01*
X69923Y-41842D01*
X69486Y-43592D01*
Y-45342D01*
X69923Y-47092D01*
X71015Y-48842D01*
X72325Y-50008D01*
X73853Y-50300D01*
X75381Y-49717D01*
X76910Y-47967D01*
G01X87641Y-50300D02*
Y-38634D01*
G01Y-40967D02*
X88733Y-39800D01*
X89825Y-38925D01*
X91353Y-38634D01*
X92444Y-38925D01*
X93755Y-39800D01*
G01X125698Y-38634D02*
Y-50300D01*
G01Y-33967D02*
X125261Y-33675D01*
Y-33092D01*
X125698Y-32800D01*
X126135Y-33092D01*
Y-33675D01*
X125698Y-33967D01*
G01X139923Y-48259D02*
X141015Y-49425D01*
X142543Y-50300D01*
X143853D01*
X145163Y-49717D01*
X146036Y-48842D01*
X146473Y-47676D01*
X146255Y-45925D01*
X145381Y-45050D01*
X141451Y-43300D01*
X140578Y-41258D01*
X141015Y-39800D01*
X141888Y-38925D01*
X143198Y-38634D01*
X144508Y-38925D01*
X145818Y-39800D01*
G01X174704Y-54675D02*
X176233Y-55842D01*
X177543Y-56133D01*
X179290Y-55550D01*
X180600Y-54092D01*
X181255Y-51466D01*
Y-38634D01*
G01Y-33967D02*
X180818Y-33675D01*
Y-33092D01*
X181255Y-32800D01*
X181691Y-33092D01*
Y-33675D01*
X181255Y-33967D01*
G01X191986Y-38634D02*
Y-46800D01*
X192860Y-48842D01*
X194170Y-50008D01*
X195698Y-50300D01*
X197226Y-50008D01*
X198536Y-48842D01*
X199410Y-46800D01*
G01Y-50300D02*
Y-38634D01*
G01X209923Y-48259D02*
X211015Y-49425D01*
X212543Y-50300D01*
X213853D01*
X215163Y-49717D01*
X216036Y-48842D01*
X216473Y-47676D01*
X216255Y-45925D01*
X215381Y-45050D01*
X211451Y-43300D01*
X210578Y-41258D01*
X211015Y-39800D01*
X211888Y-38925D01*
X213198Y-38634D01*
X214508Y-38925D01*
X215818Y-39800D01*
G01X230698Y-32800D02*
Y-50300D01*
G01X227641Y-38634D02*
X233755D01*
G01X264388Y-50300D02*
Y-35425D01*
X264825Y-33967D01*
X265698Y-33092D01*
X267008Y-32800D01*
X268318Y-33383D01*
X268973Y-34842D01*
G01X266353Y-39800D02*
X261986D01*
G01X283198Y-50300D02*
X281888Y-50008D01*
X280578Y-48842D01*
X279704Y-46800D01*
X279268Y-44467D01*
X279704Y-42133D01*
X280578Y-40092D01*
X281888Y-38925D01*
X283198Y-38634D01*
X284508Y-38925D01*
X285818Y-40092D01*
X286691Y-42133D01*
X286910Y-44467D01*
X286691Y-46800D01*
X285818Y-48842D01*
X284508Y-50008D01*
X283198Y-50300D01*
G01X297641D02*
Y-38634D01*
G01Y-40967D02*
X298733Y-39800D01*
X299825Y-38925D01*
X301353Y-38634D01*
X302444Y-38925D01*
X303755Y-39800D01*
G01X331113Y-55550D02*
X332423Y-56133D01*
X334170Y-55550D01*
X335261Y-54384D01*
X336135Y-52925D01*
X337444Y-48259D01*
X340283Y-38634D01*
G01X333296D02*
X337444Y-48259D01*
G01X353198Y-50300D02*
X351888Y-50008D01*
X350578Y-48842D01*
X349704Y-46800D01*
X349268Y-44467D01*
X349704Y-42133D01*
X350578Y-40092D01*
X351888Y-38925D01*
X353198Y-38634D01*
X354508Y-38925D01*
X355818Y-40092D01*
X356691Y-42133D01*
X356910Y-44467D01*
X356691Y-46800D01*
X355818Y-48842D01*
X354508Y-50008D01*
X353198Y-50300D01*
G01X366986Y-38634D02*
Y-46800D01*
X367860Y-48842D01*
X369170Y-50008D01*
X370698Y-50300D01*
X372226Y-50008D01*
X373536Y-48842D01*
X374410Y-46800D01*
G01Y-50300D02*
Y-38634D01*
G01X385141Y-50300D02*
Y-38634D01*
G01Y-40967D02*
X386233Y-39800D01*
X387325Y-38925D01*
X388853Y-38634D01*
X389944Y-38925D01*
X391255Y-39800D01*
G01X420141Y-50300D02*
Y-38634D01*
G01Y-40967D02*
X421233Y-39800D01*
X422325Y-38925D01*
X423853Y-38634D01*
X424944Y-38925D01*
X426255Y-39800D01*
G01X437423Y-42425D02*
X444410D01*
X443755Y-40383D01*
X442663Y-39217D01*
X441135Y-38634D01*
X439606Y-38925D01*
X438296Y-39800D01*
X437423Y-41842D01*
X436986Y-43592D01*
Y-45342D01*
X437423Y-47092D01*
X438515Y-48842D01*
X439825Y-50008D01*
X441353Y-50300D01*
X442881Y-49717D01*
X444410Y-47967D01*
G01X456888Y-50300D02*
Y-35425D01*
X457325Y-33967D01*
X458198Y-33092D01*
X459508Y-32800D01*
X460818Y-33383D01*
X461473Y-34842D01*
G01X458853Y-39800D02*
X454486D01*
G01X472423Y-42425D02*
X479410D01*
X478755Y-40383D01*
X477663Y-39217D01*
X476135Y-38634D01*
X474606Y-38925D01*
X473296Y-39800D01*
X472423Y-41842D01*
X471986Y-43592D01*
Y-45342D01*
X472423Y-47092D01*
X473515Y-48842D01*
X474825Y-50008D01*
X476353Y-50300D01*
X477881Y-49717D01*
X479410Y-47967D01*
G01X490141Y-50300D02*
Y-38634D01*
G01Y-40967D02*
X491233Y-39800D01*
X492325Y-38925D01*
X493853Y-38634D01*
X494944Y-38925D01*
X496255Y-39800D01*
G01X507423Y-42425D02*
X514410D01*
X513755Y-40383D01*
X512663Y-39217D01*
X511135Y-38634D01*
X509606Y-38925D01*
X508296Y-39800D01*
X507423Y-41842D01*
X506986Y-43592D01*
Y-45342D01*
X507423Y-47092D01*
X508515Y-48842D01*
X509825Y-50008D01*
X511353Y-50300D01*
X512881Y-49717D01*
X514410Y-47967D01*
G01X524486Y-50300D02*
Y-38634D01*
G01Y-41550D02*
X525360Y-40092D01*
X526670Y-38925D01*
X528416Y-38634D01*
X529944Y-38925D01*
X531255Y-40092D01*
X531910Y-42133D01*
Y-50300D01*
G01X549191Y-40092D02*
X547663Y-38925D01*
X546353Y-38634D01*
X544606Y-39217D01*
X543296Y-40383D01*
X542423Y-42425D01*
X542204Y-44467D01*
X542423Y-46509D01*
X543296Y-48259D01*
X544606Y-49717D01*
X546353Y-50300D01*
X547881Y-49717D01*
X549191Y-48550D01*
G01X559923Y-42425D02*
X566910D01*
X566255Y-40383D01*
X565163Y-39217D01*
X563635Y-38634D01*
X562106Y-38925D01*
X560796Y-39800D01*
X559923Y-41842D01*
X559486Y-43592D01*
Y-45342D01*
X559923Y-47092D01*
X561015Y-48842D01*
X562325Y-50008D01*
X563853Y-50300D01*
X565381Y-49717D01*
X566910Y-47967D01*
G01X598198Y-32800D02*
Y-50300D01*
G01X595141Y-38634D02*
X601255D01*
G01X615698Y-50300D02*
X614388Y-50008D01*
X613078Y-48842D01*
X612204Y-46800D01*
X611768Y-44467D01*
X612204Y-42133D01*
X613078Y-40092D01*
X614388Y-38925D01*
X615698Y-38634D01*
X617008Y-38925D01*
X618318Y-40092D01*
X619191Y-42133D01*
X619410Y-44467D01*
X619191Y-46800D01*
X618318Y-48842D01*
X617008Y-50008D01*
X615698Y-50300D01*
G01X649388D02*
Y-35425D01*
X649825Y-33967D01*
X650698Y-33092D01*
X652008Y-32800D01*
X653318Y-33383D01*
X653973Y-34842D01*
G01X651353Y-39800D02*
X646986D01*
G01X668198Y-38634D02*
Y-50300D01*
G01Y-33967D02*
X667761Y-33675D01*
Y-33092D01*
X668198Y-32800D01*
X668635Y-33092D01*
Y-33675D01*
X668198Y-33967D01*
G01X681986Y-50300D02*
Y-38634D01*
G01Y-41550D02*
X682860Y-40092D01*
X684170Y-38925D01*
X685916Y-38634D01*
X687444Y-38925D01*
X688755Y-40092D01*
X689410Y-42133D01*
Y-50300D01*
G01X707128Y-32800D02*
Y-50300D01*
G01Y-47676D02*
X706255Y-49134D01*
X704944Y-50008D01*
X703416Y-50300D01*
X701670Y-49717D01*
X700360Y-48259D01*
X699486Y-46509D01*
X699268Y-44467D01*
X699486Y-42425D01*
X700360Y-40675D01*
X701670Y-39217D01*
X703416Y-38634D01*
X704944Y-38925D01*
X706036Y-39509D01*
X707128Y-40675D01*
G01X738198Y-32800D02*
Y-50300D01*
G01X735141Y-38634D02*
X741255D01*
G01X751986Y-50300D02*
Y-32800D01*
G01Y-41258D02*
X753078Y-39800D01*
X754170Y-38925D01*
X755916Y-38634D01*
X757226Y-38925D01*
X758755Y-40092D01*
X759410Y-41842D01*
Y-50300D01*
G01X769923Y-42425D02*
X776910D01*
X776255Y-40383D01*
X775163Y-39217D01*
X773635Y-38634D01*
X772106Y-38925D01*
X770796Y-39800D01*
X769923Y-41842D01*
X769486Y-43592D01*
Y-45342D01*
X769923Y-47092D01*
X771015Y-48842D01*
X772325Y-50008D01*
X773853Y-50300D01*
X775381Y-49717D01*
X776910Y-47967D01*
G01X803613D02*
X805360Y-49425D01*
X807325Y-50300D01*
X809071D01*
X810818Y-49425D01*
X812128Y-47967D01*
X812783Y-45925D01*
X812346Y-43884D01*
X811255Y-42133D01*
X809290Y-40967D01*
X806670Y-40383D01*
X805141Y-39217D01*
X804486Y-37175D01*
X804923Y-35133D01*
X806015Y-33675D01*
X807543Y-32800D01*
X809071D01*
X810600Y-33383D01*
X811910Y-34842D01*
G01X830065Y-50300D02*
X821331D01*
Y-32800D01*
X830065D01*
G01X826571Y-41258D02*
X821331D01*
G01X860698Y-38634D02*
Y-50300D01*
G01Y-33967D02*
X860261Y-33675D01*
Y-33092D01*
X860698Y-32800D01*
X861135Y-33092D01*
Y-33675D01*
X860698Y-33967D01*
G01X871648Y-50300D02*
Y-38634D01*
G01Y-41842D02*
X872303Y-40383D01*
X873395Y-39217D01*
X874923Y-38634D01*
X876451Y-39217D01*
X877543Y-40383D01*
X878198Y-41842D01*
Y-50300D01*
G01Y-41842D02*
X878853Y-40383D01*
X879944Y-39217D01*
X881473Y-38634D01*
X883001Y-39217D01*
X884093Y-40383D01*
X884748Y-42133D01*
Y-50300D01*
G01X891768Y-56133D02*
Y-38634D01*
G01Y-41258D02*
X892860Y-39800D01*
X893951Y-38925D01*
X895698Y-38634D01*
X897226Y-38925D01*
X898755Y-40383D01*
X899410Y-42425D01*
X899628Y-44467D01*
X899410Y-46509D01*
X898755Y-48550D01*
X897444Y-49717D01*
X895698Y-50300D01*
X894170Y-50008D01*
X892641Y-49134D01*
X891768Y-47967D01*
G01X909923Y-42425D02*
X916910D01*
X916255Y-40383D01*
X915163Y-39217D01*
X913635Y-38634D01*
X912106Y-38925D01*
X910796Y-39800D01*
X909923Y-41842D01*
X909486Y-43592D01*
Y-45342D01*
X909923Y-47092D01*
X911015Y-48842D01*
X912325Y-50008D01*
X913853Y-50300D01*
X915381Y-49717D01*
X916910Y-47967D01*
G01X934628Y-32800D02*
Y-50300D01*
G01Y-47676D02*
X933755Y-49134D01*
X932444Y-50008D01*
X930916Y-50300D01*
X929170Y-49717D01*
X927860Y-48259D01*
X926986Y-46509D01*
X926768Y-44467D01*
X926986Y-42425D01*
X927860Y-40675D01*
X929170Y-39217D01*
X930916Y-38634D01*
X932444Y-38925D01*
X933536Y-39509D01*
X934628Y-40675D01*
G01X952128Y-50300D02*
Y-38634D01*
G01Y-40675D02*
X951255Y-39509D01*
X949944Y-38925D01*
X948416Y-38634D01*
X946888Y-39217D01*
X945578Y-40383D01*
X944704Y-42133D01*
X944268Y-44467D01*
X944704Y-46800D01*
X945578Y-48550D01*
X946888Y-49717D01*
X948416Y-50300D01*
X949944Y-50008D01*
X951255Y-49134D01*
X952128Y-47967D01*
G01X961986Y-50300D02*
Y-38634D01*
G01Y-41550D02*
X962860Y-40092D01*
X964170Y-38925D01*
X965916Y-38634D01*
X967444Y-38925D01*
X968755Y-40092D01*
X969410Y-42133D01*
Y-50300D01*
G01X986691Y-40092D02*
X985163Y-38925D01*
X983853Y-38634D01*
X982106Y-39217D01*
X980796Y-40383D01*
X979923Y-42425D01*
X979704Y-44467D01*
X979923Y-46509D01*
X980796Y-48259D01*
X982106Y-49717D01*
X983853Y-50300D01*
X985381Y-49717D01*
X986691Y-48550D01*
G01X997423Y-42425D02*
X1004410D01*
X1003755Y-40383D01*
X1002663Y-39217D01*
X1001135Y-38634D01*
X999606Y-38925D01*
X998296Y-39800D01*
X997423Y-41842D01*
X996986Y-43592D01*
Y-45342D01*
X997423Y-47092D01*
X998515Y-48842D01*
X999825Y-50008D01*
X1001353Y-50300D01*
X1002881Y-49717D01*
X1004410Y-47967D01*
G01X1035698Y-32800D02*
Y-50300D01*
G01X1032641Y-38634D02*
X1038755D01*
G01X1050141Y-50300D02*
Y-38634D01*
G01Y-40967D02*
X1051233Y-39800D01*
X1052325Y-38925D01*
X1053853Y-38634D01*
X1054944Y-38925D01*
X1056255Y-39800D01*
G01X1074628Y-50300D02*
Y-38634D01*
G01Y-40675D02*
X1073755Y-39509D01*
X1072444Y-38925D01*
X1070916Y-38634D01*
X1069388Y-39217D01*
X1068078Y-40383D01*
X1067204Y-42133D01*
X1066768Y-44467D01*
X1067204Y-46800D01*
X1068078Y-48550D01*
X1069388Y-49717D01*
X1070916Y-50300D01*
X1072444Y-50008D01*
X1073755Y-49134D01*
X1074628Y-47967D01*
G01X1091691Y-40092D02*
X1090163Y-38925D01*
X1088853Y-38634D01*
X1087106Y-39217D01*
X1085796Y-40383D01*
X1084923Y-42425D01*
X1084704Y-44467D01*
X1084923Y-46509D01*
X1085796Y-48259D01*
X1087106Y-49717D01*
X1088853Y-50300D01*
X1090381Y-49717D01*
X1091691Y-48550D01*
G01X1102423Y-42425D02*
X1109410D01*
X1108755Y-40383D01*
X1107663Y-39217D01*
X1106135Y-38634D01*
X1104606Y-38925D01*
X1103296Y-39800D01*
X1102423Y-41842D01*
X1101986Y-43592D01*
Y-45342D01*
X1102423Y-47092D01*
X1103515Y-48842D01*
X1104825Y-50008D01*
X1106353Y-50300D01*
X1107881Y-49717D01*
X1109410Y-47967D01*
G01X1119923Y-48259D02*
X1121015Y-49425D01*
X1122543Y-50300D01*
X1123853D01*
X1125163Y-49717D01*
X1126036Y-48842D01*
X1126473Y-47676D01*
X1126255Y-45925D01*
X1125381Y-45050D01*
X1121451Y-43300D01*
X1120578Y-41258D01*
X1121015Y-39800D01*
X1121888Y-38925D01*
X1123198Y-38634D01*
X1124508Y-38925D01*
X1125818Y-39800D01*
G01X1158198Y-38634D02*
Y-50300D01*
G01Y-33967D02*
X1157761Y-33675D01*
Y-33092D01*
X1158198Y-32800D01*
X1158635Y-33092D01*
Y-33675D01*
X1158198Y-33967D01*
G01X1171986Y-50300D02*
Y-38634D01*
G01Y-41550D02*
X1172860Y-40092D01*
X1174170Y-38925D01*
X1175916Y-38634D01*
X1177444Y-38925D01*
X1178755Y-40092D01*
X1179410Y-42133D01*
Y-50300D01*
G01X1210698D02*
Y-32800D01*
G01X1232128Y-50300D02*
Y-38634D01*
G01Y-40675D02*
X1231255Y-39509D01*
X1229944Y-38925D01*
X1228416Y-38634D01*
X1226888Y-39217D01*
X1225578Y-40383D01*
X1224704Y-42133D01*
X1224268Y-44467D01*
X1224704Y-46800D01*
X1225578Y-48550D01*
X1226888Y-49717D01*
X1228416Y-50300D01*
X1229944Y-50008D01*
X1231255Y-49134D01*
X1232128Y-47967D01*
G01X1241113Y-55550D02*
X1242423Y-56133D01*
X1244170Y-55550D01*
X1245261Y-54384D01*
X1246135Y-52925D01*
X1247444Y-48259D01*
X1250283Y-38634D01*
G01X1243296D02*
X1247444Y-48259D01*
G01X1259923Y-42425D02*
X1266910D01*
X1266255Y-40383D01*
X1265163Y-39217D01*
X1263635Y-38634D01*
X1262106Y-38925D01*
X1260796Y-39800D01*
X1259923Y-41842D01*
X1259486Y-43592D01*
Y-45342D01*
X1259923Y-47092D01*
X1261015Y-48842D01*
X1262325Y-50008D01*
X1263853Y-50300D01*
X1265381Y-49717D01*
X1266910Y-47967D01*
G01X1277641Y-50300D02*
Y-38634D01*
G01Y-40967D02*
X1278733Y-39800D01*
X1279825Y-38925D01*
X1281353Y-38634D01*
X1282444Y-38925D01*
X1283755Y-39800D01*
G01X1311331Y-32800D02*
Y-50300D01*
X1320065D01*
G01X1333198D02*
X1334726Y-50008D01*
X1336473Y-49134D01*
X1337565Y-47676D01*
X1338001Y-45633D01*
X1337565Y-43592D01*
X1336255Y-41842D01*
X1334290Y-40967D01*
X1332106D01*
X1330796Y-40383D01*
X1329704Y-38925D01*
X1329268Y-36884D01*
X1329923Y-34842D01*
X1331451Y-33383D01*
X1333198Y-32800D01*
X1334944Y-33383D01*
X1336473Y-34842D01*
X1337128Y-36884D01*
X1336691Y-38925D01*
X1335600Y-40383D01*
X1334290Y-40967D01*
X1332106D01*
X1330141Y-41842D01*
X1328831Y-43592D01*
X1328395Y-45633D01*
X1328831Y-47676D01*
X1329923Y-49134D01*
X1331670Y-50008D01*
X1333198Y-50300D01*
G01X1350698Y-50883D02*
X1350261Y-50592D01*
Y-50008D01*
X1350698Y-49717D01*
X1351135Y-50008D01*
Y-50592D01*
X1350698Y-50883D01*
G01X1201883Y1950376D02*
X1207123D01*
G01X1204503D02*
Y1932876D01*
G01X1201883D02*
X1207123D01*
G01X1216326D02*
Y1950376D01*
X1222003Y1935793D01*
X1227680Y1950376D01*
Y1932876D01*
G01X1235136D02*
Y1950376D01*
X1240376D01*
X1242123Y1949501D01*
X1243433Y1947459D01*
X1243870Y1945126D01*
X1243433Y1942793D01*
X1242341Y1941043D01*
X1240376Y1940167D01*
X1235136D01*
G01X1255911Y1927043D02*
X1253728Y1929959D01*
X1252636Y1932876D01*
Y1944542D01*
X1253728Y1947459D01*
X1255911Y1950376D01*
G01X1274503Y1932876D02*
X1272756Y1933168D01*
X1271228Y1934334D01*
X1269918Y1936084D01*
X1269044Y1938126D01*
X1268608Y1940459D01*
Y1942793D01*
X1269044Y1945126D01*
X1269918Y1947168D01*
X1271228Y1948917D01*
X1272756Y1950084D01*
X1274503Y1950376D01*
X1276249Y1950084D01*
X1277778Y1948917D01*
X1279088Y1947168D01*
X1279962Y1945126D01*
X1280398Y1942793D01*
Y1940459D01*
X1279962Y1938126D01*
X1279088Y1936084D01*
X1277778Y1934334D01*
X1276249Y1933168D01*
X1274503Y1932876D01*
G01X1288291D02*
Y1950376D01*
G01Y1941918D02*
X1289383Y1943376D01*
X1290475Y1944251D01*
X1292221Y1944542D01*
X1293531Y1944251D01*
X1295060Y1943084D01*
X1295715Y1941334D01*
Y1932876D01*
G01X1302953D02*
Y1944542D01*
G01Y1941334D02*
X1303608Y1942793D01*
X1304700Y1943959D01*
X1306228Y1944542D01*
X1307756Y1943959D01*
X1308848Y1942793D01*
X1309503Y1941334D01*
Y1932876D01*
G01Y1941334D02*
X1310158Y1942793D01*
X1311249Y1943959D01*
X1312778Y1944542D01*
X1314306Y1943959D01*
X1315398Y1942793D01*
X1316053Y1941043D01*
Y1932876D01*
G01X1328095Y1927043D02*
X1330278Y1929959D01*
X1331370Y1932876D01*
Y1944542D01*
X1330278Y1947459D01*
X1328095Y1950376D01*
G01X1180218Y1969859D02*
X1181965Y1968401D01*
X1183930Y1967526D01*
X1185676D01*
X1187423Y1968401D01*
X1188733Y1969859D01*
X1189388Y1971901D01*
X1188951Y1973942D01*
X1187860Y1975693D01*
X1185895Y1976859D01*
X1183275Y1977443D01*
X1181746Y1978609D01*
X1181091Y1980651D01*
X1181528Y1982693D01*
X1182620Y1984151D01*
X1184148Y1985026D01*
X1185676D01*
X1187205Y1984443D01*
X1188515Y1982984D01*
G01X1206670Y1967526D02*
X1197936D01*
Y1985026D01*
X1206670D01*
G01X1203176Y1976568D02*
X1197936D01*
G01X1234683Y1985026D02*
X1239923D01*
G01X1237303D02*
Y1967526D01*
G01X1234683D02*
X1239923D01*
G01X1249126D02*
Y1985026D01*
X1254803Y1970443D01*
X1260480Y1985026D01*
Y1967526D01*
G01X1267936D02*
Y1985026D01*
X1273176D01*
X1274923Y1984151D01*
X1276233Y1982109D01*
X1276670Y1979776D01*
X1276233Y1977443D01*
X1275141Y1975693D01*
X1273176Y1974817D01*
X1267936D01*
G01X1294170Y1967526D02*
X1285436D01*
Y1985026D01*
X1294170D01*
G01X1290676Y1976568D02*
X1285436D01*
G01X1302500Y1967526D02*
Y1985026D01*
X1306866D01*
X1308613Y1984151D01*
X1309923Y1982984D01*
X1311015Y1981235D01*
X1311888Y1979192D01*
X1312106Y1976276D01*
X1311888Y1973359D01*
X1311015Y1971317D01*
X1309923Y1969567D01*
X1308613Y1968401D01*
X1306866Y1967526D01*
X1302500D01*
G01X1319344D02*
X1324803Y1985026D01*
X1330262Y1967526D01*
G01X1328296Y1973651D02*
X1321309D01*
G01X1337281Y1967526D02*
Y1985026D01*
X1347325Y1967526D01*
Y1985026D01*
G01X1364606Y1983567D02*
X1363296Y1984443D01*
X1361768Y1985026D01*
X1360021D01*
X1358056Y1984151D01*
X1356528Y1982693D01*
X1355436Y1980942D01*
X1354563Y1978026D01*
X1354344Y1975401D01*
X1354781Y1972776D01*
X1355436Y1971026D01*
X1356746Y1969276D01*
X1358275Y1968109D01*
X1359803Y1967526D01*
X1361331D01*
X1362860Y1968109D01*
X1364170Y1968984D01*
X1365262Y1970150D01*
G01X1381670Y1967526D02*
X1372936D01*
Y1985026D01*
X1381670D01*
G01X1378176Y1976568D02*
X1372936D01*
G01X1412303Y1985026D02*
Y1967526D01*
G01X1407281Y1985026D02*
X1417325D01*
G01X1424344Y1967526D02*
X1429803Y1985026D01*
X1435262Y1967526D01*
G01X1433296Y1973651D02*
X1426309D01*
G01X1449049Y1976859D02*
X1449923Y1977734D01*
X1450578Y1979192D01*
X1451015Y1981235D01*
X1450578Y1982984D01*
X1449705Y1984151D01*
X1448176Y1985026D01*
X1442281D01*
Y1967526D01*
X1449486D01*
X1451015Y1968692D01*
X1451888Y1970443D01*
X1452325Y1972484D01*
X1451888Y1974526D01*
X1450578Y1976276D01*
X1449049Y1976859D01*
X1442281D01*
G01X1460436Y1985026D02*
Y1967526D01*
X1469170D01*
G01X1486670D02*
X1477936D01*
Y1985026D01*
X1486670D01*
G01X1483176Y1976568D02*
X1477936D01*
G01X1499803Y1966943D02*
X1499366Y1967234D01*
Y1967818D01*
X1499803Y1968109D01*
X1500240Y1967818D01*
Y1967234D01*
X1499803Y1966943D01*
G01Y1974817D02*
X1499366Y1975109D01*
Y1975693D01*
X1499803Y1975984D01*
X1500240Y1975693D01*
Y1975109D01*
X1499803Y1974817D01*
G01X1530436Y1985026D02*
Y1967526D01*
X1539170D01*
G01X1552303D02*
X1553831Y1967818D01*
X1555578Y1968692D01*
X1556670Y1970150D01*
X1557106Y1972193D01*
X1556670Y1974234D01*
X1555360Y1975984D01*
X1553395Y1976859D01*
X1551211D01*
X1549901Y1977443D01*
X1548809Y1978901D01*
X1548373Y1980942D01*
X1549028Y1982984D01*
X1550556Y1984443D01*
X1552303Y1985026D01*
X1554049Y1984443D01*
X1555578Y1982984D01*
X1556233Y1980942D01*
X1555796Y1978901D01*
X1554705Y1977443D01*
X1553395Y1976859D01*
X1551211D01*
X1549246Y1975984D01*
X1547936Y1974234D01*
X1547500Y1972193D01*
X1547936Y1970150D01*
X1549028Y1968692D01*
X1550775Y1967818D01*
X1552303Y1967526D01*
G01X1234700Y1900850D02*
X1236009Y1899392D01*
X1237538Y1898518D01*
X1239503Y1898226D01*
X1241468Y1898809D01*
X1242996Y1899976D01*
X1244088Y1902017D01*
X1244306Y1904351D01*
X1243870Y1906684D01*
X1242778Y1908143D01*
X1241249Y1909309D01*
X1239721Y1909601D01*
X1238193Y1909309D01*
X1236228Y1908143D01*
X1236883Y1915726D01*
X1242778D01*
G01X1257003D02*
X1255256Y1915143D01*
X1253946Y1913684D01*
X1253073Y1911935D01*
X1252418Y1909601D01*
X1252200Y1906976D01*
X1252418Y1904351D01*
X1253073Y1902017D01*
X1253946Y1900267D01*
X1255256Y1898809D01*
X1257003Y1898226D01*
X1258749Y1898809D01*
X1260060Y1900267D01*
X1260933Y1902017D01*
X1261588Y1904351D01*
X1261806Y1906976D01*
X1261588Y1909601D01*
X1260933Y1911935D01*
X1260060Y1913684D01*
X1258749Y1915143D01*
X1257003Y1915726D01*
G01X1274503Y1897643D02*
X1274066Y1897934D01*
Y1898518D01*
X1274503Y1898809D01*
X1274940Y1898518D01*
Y1897934D01*
X1274503Y1897643D01*
G01X1292003Y1915726D02*
X1290256Y1915143D01*
X1288946Y1913684D01*
X1288073Y1911935D01*
X1287418Y1909601D01*
X1287200Y1906976D01*
X1287418Y1904351D01*
X1288073Y1902017D01*
X1288946Y1900267D01*
X1290256Y1898809D01*
X1292003Y1898226D01*
X1293749Y1898809D01*
X1295060Y1900267D01*
X1295933Y1902017D01*
X1296588Y1904351D01*
X1296806Y1906976D01*
X1296588Y1909601D01*
X1295933Y1911935D01*
X1295060Y1913684D01*
X1293749Y1915143D01*
X1292003Y1915726D01*
G01X1372953Y1950376D02*
X1376009Y1932876D01*
X1379503Y1950376D01*
X1382996Y1932876D01*
X1386053Y1950376D01*
G01X1394383D02*
X1399623D01*
G01X1397003D02*
Y1932876D01*
G01X1394383D02*
X1399623D01*
G01X1409700D02*
Y1950376D01*
X1414066D01*
X1415813Y1949501D01*
X1417123Y1948334D01*
X1418215Y1946585D01*
X1419088Y1944542D01*
X1419306Y1941626D01*
X1419088Y1938709D01*
X1418215Y1936667D01*
X1417123Y1934917D01*
X1415813Y1933751D01*
X1414066Y1932876D01*
X1409700D01*
G01X1432003Y1950376D02*
Y1932876D01*
G01X1426981Y1950376D02*
X1437025D01*
G01X1444918Y1932876D02*
Y1950376D01*
G01X1454088D02*
Y1932876D01*
G01Y1941626D02*
X1444918D01*
G01X1465911Y1927043D02*
X1463728Y1929959D01*
X1462636Y1932876D01*
Y1944542D01*
X1463728Y1947459D01*
X1465911Y1950376D01*
G01X1477953Y1932876D02*
Y1944542D01*
G01Y1941334D02*
X1478608Y1942793D01*
X1479700Y1943959D01*
X1481228Y1944542D01*
X1482756Y1943959D01*
X1483848Y1942793D01*
X1484503Y1941334D01*
Y1932876D01*
G01Y1941334D02*
X1485158Y1942793D01*
X1486249Y1943959D01*
X1487778Y1944542D01*
X1489306Y1943959D01*
X1490398Y1942793D01*
X1491053Y1941043D01*
Y1932876D01*
G01X1502003Y1944542D02*
Y1932876D01*
G01Y1949209D02*
X1501566Y1949501D01*
Y1950084D01*
X1502003Y1950376D01*
X1502440Y1950084D01*
Y1949501D01*
X1502003Y1949209D01*
G01X1519503Y1932876D02*
Y1950376D01*
G01X1533728Y1934917D02*
X1534820Y1933751D01*
X1536348Y1932876D01*
X1537658D01*
X1538968Y1933459D01*
X1539841Y1934334D01*
X1540278Y1935500D01*
X1540060Y1937251D01*
X1539186Y1938126D01*
X1535256Y1939876D01*
X1534383Y1941918D01*
X1534820Y1943376D01*
X1535693Y1944251D01*
X1537003Y1944542D01*
X1538313Y1944251D01*
X1539623Y1943376D01*
G01X1555595Y1927043D02*
X1557778Y1929959D01*
X1558870Y1932876D01*
Y1944542D01*
X1557778Y1947459D01*
X1555595Y1950376D01*
G01X1436605Y1905517D02*
X1438133Y1907559D01*
X1439443Y1908726D01*
X1441190Y1909309D01*
X1442718Y1908726D01*
X1443810Y1907559D01*
X1444683Y1905809D01*
X1444901Y1903768D01*
X1444683Y1902017D01*
X1443810Y1900267D01*
X1442499Y1898809D01*
X1440971Y1898226D01*
X1439225Y1898809D01*
X1437696Y1900559D01*
X1436823Y1903184D01*
X1436605Y1906101D01*
X1437041Y1909892D01*
X1437696Y1911935D01*
X1438788Y1913976D01*
X1440316Y1915434D01*
X1441845Y1915726D01*
X1443373Y1915143D01*
X1444465Y1913684D01*
G01X1458253Y1897643D02*
X1457816Y1897934D01*
Y1898518D01*
X1458253Y1898809D01*
X1458690Y1898518D01*
Y1897934D01*
X1458253Y1897643D01*
G01X1475316Y1898226D02*
X1475753Y1902017D01*
X1476408Y1905226D01*
X1477281Y1908143D01*
X1478373Y1911351D01*
X1480120Y1915726D01*
X1471386D01*
G01X1488450Y1900850D02*
X1489759Y1899392D01*
X1491288Y1898518D01*
X1493253Y1898226D01*
X1495218Y1898809D01*
X1496746Y1899976D01*
X1497838Y1902017D01*
X1498056Y1904351D01*
X1497620Y1906684D01*
X1496528Y1908143D01*
X1494999Y1909309D01*
X1493471Y1909601D01*
X1491943Y1909309D01*
X1489978Y1908143D01*
X1490633Y1915726D01*
X1496528D01*
G01X1607003Y1950376D02*
Y1932876D01*
G01X1601981Y1950376D02*
X1612025D01*
G01X1624503Y1932876D02*
Y1940751D01*
X1620136Y1950376D01*
G01X1628870D02*
X1624503Y1940751D01*
G01X1637636Y1932876D02*
Y1950376D01*
X1642876D01*
X1644623Y1949501D01*
X1645933Y1947459D01*
X1646370Y1945126D01*
X1645933Y1942793D01*
X1644841Y1941043D01*
X1642876Y1940167D01*
X1637636D01*
G01X1663870Y1932876D02*
X1655136D01*
Y1950376D01*
X1663870D01*
G01X1660376Y1941918D02*
X1655136D01*
G01X1619918Y1900559D02*
X1621665Y1899101D01*
X1623630Y1898226D01*
X1625376D01*
X1627123Y1899101D01*
X1628433Y1900559D01*
X1629088Y1902601D01*
X1628651Y1904642D01*
X1627560Y1906393D01*
X1625595Y1907559D01*
X1622975Y1908143D01*
X1621446Y1909309D01*
X1620791Y1911351D01*
X1621228Y1913393D01*
X1622320Y1914851D01*
X1623848Y1915726D01*
X1625376D01*
X1626905Y1915143D01*
X1628215Y1913684D01*
G01X1646370Y1898226D02*
X1637636D01*
Y1915726D01*
X1646370D01*
G01X1642876Y1907268D02*
X1637636D01*
G01X1707636Y1932876D02*
Y1950376D01*
X1713095D01*
X1714841Y1949501D01*
X1715933Y1948334D01*
X1716370Y1946001D01*
X1715933Y1943667D01*
X1714623Y1942209D01*
X1713095Y1941334D01*
X1707636D01*
G01X1713095D02*
X1716370Y1932876D01*
G01X1726228Y1940751D02*
X1733215D01*
X1732560Y1942793D01*
X1731468Y1943959D01*
X1729940Y1944542D01*
X1728411Y1944251D01*
X1727101Y1943376D01*
X1726228Y1941334D01*
X1725791Y1939584D01*
Y1937834D01*
X1726228Y1936084D01*
X1727320Y1934334D01*
X1728630Y1933168D01*
X1730158Y1932876D01*
X1731686Y1933459D01*
X1733215Y1935209D01*
G01X1745693Y1932876D02*
Y1947751D01*
X1746130Y1949209D01*
X1747003Y1950084D01*
X1748313Y1950376D01*
X1749623Y1949793D01*
X1750278Y1948334D01*
G01X1747658Y1943376D02*
X1743291D01*
G01X1764503Y1932293D02*
X1764066Y1932584D01*
Y1933168D01*
X1764503Y1933459D01*
X1764940Y1933168D01*
Y1932584D01*
X1764503Y1932293D01*
G01X1795136Y1932876D02*
Y1950376D01*
X1800376D01*
X1802123Y1949501D01*
X1803433Y1947459D01*
X1803870Y1945126D01*
X1803433Y1942793D01*
X1802341Y1941043D01*
X1800376Y1940167D01*
X1795136D01*
G01X1817003Y1932876D02*
Y1950376D01*
G01X1838433Y1932876D02*
Y1944542D01*
G01Y1942501D02*
X1837560Y1943667D01*
X1836249Y1944251D01*
X1834721Y1944542D01*
X1833193Y1943959D01*
X1831883Y1942793D01*
X1831009Y1941043D01*
X1830573Y1938709D01*
X1831009Y1936376D01*
X1831883Y1934626D01*
X1833193Y1933459D01*
X1834721Y1932876D01*
X1836249Y1933168D01*
X1837560Y1934042D01*
X1838433Y1935209D01*
G01X1848291Y1932876D02*
Y1944542D01*
G01Y1941626D02*
X1849165Y1943084D01*
X1850475Y1944251D01*
X1852221Y1944542D01*
X1853749Y1944251D01*
X1855060Y1943084D01*
X1855715Y1941043D01*
Y1932876D01*
G01X1866228Y1940751D02*
X1873215D01*
X1872560Y1942793D01*
X1871468Y1943959D01*
X1869940Y1944542D01*
X1868411Y1944251D01*
X1867101Y1943376D01*
X1866228Y1941334D01*
X1865791Y1939584D01*
Y1937834D01*
X1866228Y1936084D01*
X1867320Y1934334D01*
X1868630Y1933168D01*
X1870158Y1932876D01*
X1871686Y1933459D01*
X1873215Y1935209D01*
G01X1777636Y1915726D02*
Y1898226D01*
X1786370D01*
G01X1799066D02*
X1799503Y1902017D01*
X1800158Y1905226D01*
X1801031Y1908143D01*
X1802123Y1911351D01*
X1803870Y1915726D01*
X1795136D01*
G01X1912500Y1932293D02*
X1922106Y1945126D01*
G01X1917303Y1947459D02*
Y1929959D01*
G01X1922106Y1932293D02*
X1912500Y1945126D01*
G01X1910753Y1938709D02*
X1923853D01*
G01X1949465D02*
X1955141D01*
G01X1982500Y1932876D02*
Y1950376D01*
X1986866D01*
X1988613Y1949501D01*
X1989923Y1948334D01*
X1991015Y1946585D01*
X1991888Y1944542D01*
X1992106Y1941626D01*
X1991888Y1938709D01*
X1991015Y1936667D01*
X1989923Y1934917D01*
X1988613Y1933751D01*
X1986866Y1932876D01*
X1982500D01*
G01X2001528Y1940751D02*
X2008515D01*
X2007860Y1942793D01*
X2006768Y1943959D01*
X2005240Y1944542D01*
X2003711Y1944251D01*
X2002401Y1943376D01*
X2001528Y1941334D01*
X2001091Y1939584D01*
Y1937834D01*
X2001528Y1936084D01*
X2002620Y1934334D01*
X2003930Y1933168D01*
X2005458Y1932876D01*
X2006986Y1933459D01*
X2008515Y1935209D01*
G01X2018591Y1932876D02*
Y1944542D01*
G01Y1941626D02*
X2019465Y1943084D01*
X2020775Y1944251D01*
X2022521Y1944542D01*
X2024049Y1944251D01*
X2025360Y1943084D01*
X2026015Y1941043D01*
Y1932876D01*
G01X2039803D02*
X2038493Y1933168D01*
X2037183Y1934334D01*
X2036309Y1936376D01*
X2035873Y1938709D01*
X2036309Y1941043D01*
X2037183Y1943084D01*
X2038493Y1944251D01*
X2039803Y1944542D01*
X2041113Y1944251D01*
X2042423Y1943084D01*
X2043296Y1941043D01*
X2043515Y1938709D01*
X2043296Y1936376D01*
X2042423Y1934334D01*
X2041113Y1933168D01*
X2039803Y1932876D01*
G01X2057303Y1950376D02*
Y1932876D01*
G01X2054246Y1944542D02*
X2060360D01*
G01X2071528Y1940751D02*
X2078515D01*
X2077860Y1942793D01*
X2076768Y1943959D01*
X2075240Y1944542D01*
X2073711Y1944251D01*
X2072401Y1943376D01*
X2071528Y1941334D01*
X2071091Y1939584D01*
Y1937834D01*
X2071528Y1936084D01*
X2072620Y1934334D01*
X2073930Y1933168D01*
X2075458Y1932876D01*
X2076986Y1933459D01*
X2078515Y1935209D01*
G01X2089028Y1934917D02*
X2090120Y1933751D01*
X2091648Y1932876D01*
X2092958D01*
X2094268Y1933459D01*
X2095141Y1934334D01*
X2095578Y1935500D01*
X2095360Y1937251D01*
X2094486Y1938126D01*
X2090556Y1939876D01*
X2089683Y1941918D01*
X2090120Y1943376D01*
X2090993Y1944251D01*
X2092303Y1944542D01*
X2093613Y1944251D01*
X2094923Y1943376D01*
G01X2127303Y1950376D02*
Y1932876D01*
G01X2124246Y1944542D02*
X2130360D01*
G01X2141091Y1932876D02*
Y1950376D01*
G01Y1941918D02*
X2142183Y1943376D01*
X2143275Y1944251D01*
X2145021Y1944542D01*
X2146331Y1944251D01*
X2147860Y1943084D01*
X2148515Y1941334D01*
Y1932876D01*
G01X2166233D02*
Y1944542D01*
G01Y1942501D02*
X2165360Y1943667D01*
X2164049Y1944251D01*
X2162521Y1944542D01*
X2160993Y1943959D01*
X2159683Y1942793D01*
X2158809Y1941043D01*
X2158373Y1938709D01*
X2158809Y1936376D01*
X2159683Y1934626D01*
X2160993Y1933459D01*
X2162521Y1932876D01*
X2164049Y1933168D01*
X2165360Y1934042D01*
X2166233Y1935209D01*
G01X2179803Y1950376D02*
Y1932876D01*
G01X2176746Y1944542D02*
X2182860D01*
G01X2214803Y1950376D02*
Y1932876D01*
G01X2211746Y1944542D02*
X2217860D01*
G01X2228591Y1932876D02*
Y1950376D01*
G01Y1941918D02*
X2229683Y1943376D01*
X2230775Y1944251D01*
X2232521Y1944542D01*
X2233831Y1944251D01*
X2235360Y1943084D01*
X2236015Y1941334D01*
Y1932876D01*
G01X2249803Y1944542D02*
Y1932876D01*
G01Y1949209D02*
X2249366Y1949501D01*
Y1950084D01*
X2249803Y1950376D01*
X2250240Y1950084D01*
Y1949501D01*
X2249803Y1949209D01*
G01X2264028Y1934917D02*
X2265120Y1933751D01*
X2266648Y1932876D01*
X2267958D01*
X2269268Y1933459D01*
X2270141Y1934334D01*
X2270578Y1935500D01*
X2270360Y1937251D01*
X2269486Y1938126D01*
X2265556Y1939876D01*
X2264683Y1941918D01*
X2265120Y1943376D01*
X2265993Y1944251D01*
X2267303Y1944542D01*
X2268613Y1944251D01*
X2269923Y1943376D01*
G01X2299683Y1950376D02*
X2304923D01*
G01X2302303D02*
Y1932876D01*
G01X2299683D02*
X2304923D01*
G01X2313253D02*
Y1944542D01*
G01Y1941334D02*
X2313908Y1942793D01*
X2315000Y1943959D01*
X2316528Y1944542D01*
X2318056Y1943959D01*
X2319148Y1942793D01*
X2319803Y1941334D01*
Y1932876D01*
G01Y1941334D02*
X2320458Y1942793D01*
X2321549Y1943959D01*
X2323078Y1944542D01*
X2324606Y1943959D01*
X2325698Y1942793D01*
X2326353Y1941043D01*
Y1932876D01*
G01X2333373Y1927043D02*
Y1944542D01*
G01Y1941918D02*
X2334465Y1943376D01*
X2335556Y1944251D01*
X2337303Y1944542D01*
X2338831Y1944251D01*
X2340360Y1942793D01*
X2341015Y1940751D01*
X2341233Y1938709D01*
X2341015Y1936667D01*
X2340360Y1934626D01*
X2339049Y1933459D01*
X2337303Y1932876D01*
X2335775Y1933168D01*
X2334246Y1934042D01*
X2333373Y1935209D01*
G01X2351528Y1940751D02*
X2358515D01*
X2357860Y1942793D01*
X2356768Y1943959D01*
X2355240Y1944542D01*
X2353711Y1944251D01*
X2352401Y1943376D01*
X2351528Y1941334D01*
X2351091Y1939584D01*
Y1937834D01*
X2351528Y1936084D01*
X2352620Y1934334D01*
X2353930Y1933168D01*
X2355458Y1932876D01*
X2356986Y1933459D01*
X2358515Y1935209D01*
G01X2376233Y1950376D02*
Y1932876D01*
G01Y1935500D02*
X2375360Y1934042D01*
X2374049Y1933168D01*
X2372521Y1932876D01*
X2370775Y1933459D01*
X2369465Y1934917D01*
X2368591Y1936667D01*
X2368373Y1938709D01*
X2368591Y1940751D01*
X2369465Y1942501D01*
X2370775Y1943959D01*
X2372521Y1944542D01*
X2374049Y1944251D01*
X2375141Y1943667D01*
X2376233Y1942501D01*
G01X2393733Y1932876D02*
Y1944542D01*
G01Y1942501D02*
X2392860Y1943667D01*
X2391549Y1944251D01*
X2390021Y1944542D01*
X2388493Y1943959D01*
X2387183Y1942793D01*
X2386309Y1941043D01*
X2385873Y1938709D01*
X2386309Y1936376D01*
X2387183Y1934626D01*
X2388493Y1933459D01*
X2390021Y1932876D01*
X2391549Y1933168D01*
X2392860Y1934042D01*
X2393733Y1935209D01*
G01X2403591Y1932876D02*
Y1944542D01*
G01Y1941626D02*
X2404465Y1943084D01*
X2405775Y1944251D01*
X2407521Y1944542D01*
X2409049Y1944251D01*
X2410360Y1943084D01*
X2411015Y1941043D01*
Y1932876D01*
G01X2428296Y1943084D02*
X2426768Y1944251D01*
X2425458Y1944542D01*
X2423711Y1943959D01*
X2422401Y1942793D01*
X2421528Y1940751D01*
X2421309Y1938709D01*
X2421528Y1936667D01*
X2422401Y1934917D01*
X2423711Y1933459D01*
X2425458Y1932876D01*
X2426986Y1933459D01*
X2428296Y1934626D01*
G01X2439028Y1940751D02*
X2446015D01*
X2445360Y1942793D01*
X2444268Y1943959D01*
X2442740Y1944542D01*
X2441211Y1944251D01*
X2439901Y1943376D01*
X2439028Y1941334D01*
X2438591Y1939584D01*
Y1937834D01*
X2439028Y1936084D01*
X2440120Y1934334D01*
X2441430Y1933168D01*
X2442958Y1932876D01*
X2444486Y1933459D01*
X2446015Y1935209D01*
G01X1987303Y1909892D02*
Y1898226D01*
G01Y1914559D02*
X1986866Y1914851D01*
Y1915434D01*
X1987303Y1915726D01*
X1987740Y1915434D01*
Y1914851D01*
X1987303Y1914559D01*
G01X2001528Y1900267D02*
X2002620Y1899101D01*
X2004148Y1898226D01*
X2005458D01*
X2006768Y1898809D01*
X2007641Y1899684D01*
X2008078Y1900850D01*
X2007860Y1902601D01*
X2006986Y1903476D01*
X2003056Y1905226D01*
X2002183Y1907268D01*
X2002620Y1908726D01*
X2003493Y1909601D01*
X2004803Y1909892D01*
X2006113Y1909601D01*
X2007423Y1908726D01*
G01X2034781Y1898226D02*
Y1915726D01*
X2044825Y1898226D01*
Y1915726D01*
G01X2057303Y1898226D02*
X2055556Y1898518D01*
X2054028Y1899684D01*
X2052718Y1901434D01*
X2051844Y1903476D01*
X2051408Y1905809D01*
Y1908143D01*
X2051844Y1910476D01*
X2052718Y1912518D01*
X2054028Y1914267D01*
X2055556Y1915434D01*
X2057303Y1915726D01*
X2059049Y1915434D01*
X2060578Y1914267D01*
X2061888Y1912518D01*
X2062762Y1910476D01*
X2063198Y1908143D01*
Y1905809D01*
X2062762Y1903476D01*
X2061888Y1901434D01*
X2060578Y1899684D01*
X2059049Y1898518D01*
X2057303Y1898226D01*
G01X2074803Y1915726D02*
Y1898226D01*
G01X2069781Y1915726D02*
X2079825D01*
G01X2106091Y1909892D02*
Y1901726D01*
X2106965Y1899684D01*
X2108275Y1898518D01*
X2109803Y1898226D01*
X2111331Y1898518D01*
X2112641Y1899684D01*
X2113515Y1901726D01*
G01Y1898226D02*
Y1909892D01*
G01X2124028Y1900267D02*
X2125120Y1899101D01*
X2126648Y1898226D01*
X2127958D01*
X2129268Y1898809D01*
X2130141Y1899684D01*
X2130578Y1900850D01*
X2130360Y1902601D01*
X2129486Y1903476D01*
X2125556Y1905226D01*
X2124683Y1907268D01*
X2125120Y1908726D01*
X2125993Y1909601D01*
X2127303Y1909892D01*
X2128613Y1909601D01*
X2129923Y1908726D01*
G01X2141528Y1906101D02*
X2148515D01*
X2147860Y1908143D01*
X2146768Y1909309D01*
X2145240Y1909892D01*
X2143711Y1909601D01*
X2142401Y1908726D01*
X2141528Y1906684D01*
X2141091Y1904934D01*
Y1903184D01*
X2141528Y1901434D01*
X2142620Y1899684D01*
X2143930Y1898518D01*
X2145458Y1898226D01*
X2146986Y1898809D01*
X2148515Y1900559D01*
G01X2166233Y1915726D02*
Y1898226D01*
G01Y1900850D02*
X2165360Y1899392D01*
X2164049Y1898518D01*
X2162521Y1898226D01*
X2160775Y1898809D01*
X2159465Y1900267D01*
X2158591Y1902017D01*
X2158373Y1904059D01*
X2158591Y1906101D01*
X2159465Y1907851D01*
X2160775Y1909309D01*
X2162521Y1909892D01*
X2164049Y1909601D01*
X2165141Y1909017D01*
X2166233Y1907851D01*
G01X-7874Y0D02*
X-75552D01*
G02X-90552Y15000I0J15000D01*
G01Y519024D01*
G02X-75552Y534024I15000J0D01*
G01X-7874D01*
G01Y1030087D02*
X-75552D01*
G03X-90552Y1015087I0J-15000D01*
G01Y1001780D01*
G03X-75552Y986780I15000J0D01*
G01X-7874D01*
G01Y1992126D02*
X-75552D01*
G03X-90552Y1977126I0J-15000D01*
G01Y1915165D01*
G03X-75552Y1900165I15000J0D01*
G01X-7874D01*
G01X1023228Y1618051D02*
Y1675945D01*
G02X1028701Y1681417I5472J0D01*
G01X1033465D01*
X1037402Y1685354D01*
Y1988189D01*
G03X1033465Y1992126I-3937J0D01*
G01X3937D01*
G03X0Y1988189I0J-3937D01*
G01Y1661189D01*
X1969Y1659220D01*
X17323D01*
G02Y1650559I0J-4331D01*
G01X1969D01*
X0Y1648591D01*
Y1243866D01*
X1969Y1241898D01*
X17323D01*
G02Y1233236I0J-4331D01*
G01X1969D01*
X0Y1231268D01*
Y747803D01*
X1969Y745835D01*
X17323D01*
G02Y737173I0J-4331D01*
G01X1969D01*
X0Y735205D01*
Y3937D01*
G03X3937Y0I3937J0D01*
G01X121260D01*
X127310Y11888D01*
G03X127953Y14567I-5263J2680D01*
G01Y17717D01*
G02X139764I5906J0D01*
G01Y14567D01*
G03X140406Y11888I5906J-1D01*
G01X146457Y0D01*
X1033465D01*
G03X1037402Y3937I0J3937D01*
G01Y1424882D01*
X1033465Y1428819D01*
X1028701D01*
G02X1023228Y1434291I0J5473D01*
G01Y1609902D01*
X1021260Y1611870D01*
X993681D01*
G02Y1616083I0J2107D01*
G01X1021260D01*
X1023228Y1618051D01*
G01X-7874Y39059D02*
G03X0I3937J0D01*
G01Y8350D02*
G03X-7874I-3937J0D01*
G01D02*
Y0D01*
G01Y251657D02*
Y39059D01*
G01X0Y251657D02*
G03X-7874I-3937J0D01*
G01Y282366D02*
G03X0I3937J0D01*
G01X-7874Y494965D02*
Y282366D01*
G01Y525673D02*
G03X0I3937J0D01*
G01Y494965D02*
G03X-7874I-3937J0D01*
G01Y534024D02*
Y525673D01*
G01X0Y993079D02*
G03X-7874I-3937J0D01*
G01Y986780D02*
Y993079D01*
G01Y1023787D02*
G03X0I3937J0D01*
G01X-7874D02*
Y1030087D01*
G01Y1930791D02*
Y1900165D01*
G01X0Y1930791D02*
G03X-7874I-3937J0D01*
G01Y1961500D02*
G03X0I3937J0D01*
G01X-7874Y1992126D02*
Y1961500D01*
G01X1045276Y0D02*
X1112953D01*
G03X1127953Y15000I0J15000D01*
G01Y493259D01*
G01X1045276Y25827D02*
G03X1037402I-3937J0D01*
G01X1045276Y0D02*
Y25827D01*
G01X1037402Y56535D02*
G03X1045276I3937J0D01*
G01D02*
Y284882D01*
G01X1037402Y315591D02*
G03X1045276I3937J0D01*
G01Y284882D02*
G03X1037402I-3937J0D01*
G01X1045276Y315591D02*
Y543937D01*
G01D02*
G03X1037402I-3937J0D01*
G01Y574646D02*
G03X1045276I3937J0D01*
G01D02*
Y802992D01*
G01X1037402Y833701D02*
G03X1045276I3937J0D01*
G01Y802992D02*
G03X1037402I-3937J0D01*
G01X1045276Y833701D02*
Y1062047D01*
G01D02*
G03X1037402I-3937J0D01*
G01Y1092756D02*
G03X1045276I3937J0D01*
G01D02*
Y1321102D01*
G01D02*
G03X1037402I-3937J0D01*
G01Y1351811D02*
G03X1045276I3937J0D01*
G01D02*
Y1377638D01*
G01D02*
X1112953D01*
G02X1127953Y1362638I0J-15000D01*
G01Y501133D01*
G01X1045276Y1732598D02*
X1112953D01*
G03X1127953Y1747598I0J15000D01*
G01Y1977126D01*
G03X1112953Y1992126I-15000J0D01*
G01X1045276D01*
G01X1037402Y1767835D02*
G03X1045276I3937J0D01*
G01Y1737126D02*
G03X1037402I-3937J0D01*
G01X1045276Y1767835D02*
Y1956890D01*
G01Y1732598D02*
Y1737126D01*
G01X1037402Y1987598D02*
G03X1045276I3937J0D01*
G01Y1956890D02*
G03X1037402I-3937J0D01*
G01X1045276Y1987598D02*
Y1992126D01*
G01X1127953Y501133D02*
G03Y493259I0J-3937D01*
G54D12*
G01X34450Y772550D02*
Y358105D01*
G01D02*
X70950Y321605D01*
G01X64400Y324517D02*
X30100Y358817D01*
G01D02*
Y731900D01*
G01X62225Y323168D02*
X24675Y360718D01*
G01D02*
Y594825D01*
G01X73125Y322699D02*
X37000Y358824D01*
G01D02*
Y762000D01*
G01X60050Y322267D02*
X22500Y359817D01*
G01D02*
Y588500D01*
G01X24675Y594825D02*
X18153Y601347D01*
G01D02*
X7358D01*
G01X22500Y588500D02*
X12803Y598197D01*
G01D02*
X7358D01*
G01X27699Y737535D02*
X24535D01*
G01D02*
X17662Y730662D01*
G01D02*
X15739D01*
G01D02*
X14662Y731739D01*
G01D02*
Y732000D01*
G01D02*
X13032Y733630D01*
G01D02*
X7358D01*
G01Y774575D02*
X14250D01*
G01D02*
X15000Y773825D01*
G01D02*
X18325D01*
G01D02*
X23500Y779000D01*
G01X28000D02*
X34450Y772550D01*
G01X30100Y731900D02*
X27400Y734600D01*
G01D02*
X23262D01*
G01D02*
X17831Y729169D01*
G01D02*
X14731D01*
G01D02*
X13419Y730481D01*
G01D02*
X7358D01*
G01X29652Y783500D02*
X39500Y773652D01*
G01X37000Y762000D02*
Y773076D01*
G01D02*
X29401Y780675D01*
G01X23500Y779000D02*
X28000D01*
G01X7358Y780874D02*
X15874D01*
G01D02*
X18500Y783500D01*
G01D02*
X29652D01*
G01X29401Y780675D02*
X22675D01*
G01D02*
X17787Y775787D01*
G01D02*
X15697D01*
G01D02*
X13759Y777725D01*
G01D02*
X7358D01*
G01Y891111D02*
X14500D01*
G01D02*
X15389Y892000D01*
G01D02*
X19241D01*
G01D02*
X20766Y890475D01*
G01D02*
X29521D01*
G01D02*
X46321Y873675D01*
G01X26393Y922607D02*
X41000Y908000D01*
G01X43387Y872711D02*
X27298Y888800D01*
G01D02*
X19800D01*
G01D02*
X18000Y887000D01*
G01D02*
X15461D01*
G01D02*
X14500Y887961D01*
G01D02*
X7358D01*
G01X40087Y866913D02*
X30000Y877000D01*
G01D02*
X24401D01*
G01D02*
X22300Y879101D01*
G01D02*
Y879600D01*
G01D02*
X17089Y884811D01*
G01D02*
X7358D01*
G01X34872Y890906D02*
Y894522D01*
G01D02*
X27894Y901500D01*
G01D02*
X23567D01*
G01D02*
X22344Y900277D01*
G01D02*
Y899556D01*
G01D02*
X17048Y894260D01*
G01D02*
X7358D01*
G01Y922607D02*
X26393D01*
G01X7358Y1135205D02*
X15305D01*
G01D02*
X15700Y1135600D01*
G01D02*
X18507D01*
G01D02*
X24563Y1129544D01*
G01D02*
X34053D01*
G01D02*
X106100Y1057497D01*
G01X32335Y1122002D02*
X22650D01*
G01D02*
X18896Y1125756D01*
G01D02*
X7358D01*
G01X33971Y1131741D02*
X35400Y1133170D01*
G01D02*
X42734D01*
G01X7358Y1128906D02*
X21711D01*
G01D02*
X25423Y1125194D01*
G01D02*
X32176D01*
G01D02*
X75500Y1081870D01*
G01X81175Y1079271D02*
X33077Y1127369D01*
G01D02*
X24910D01*
G01D02*
X21779Y1130500D01*
G01D02*
X15000D01*
G01D02*
X13444Y1132056D01*
G01D02*
X7358D01*
G01X42286Y1089500D02*
X17500D01*
G01D02*
X12740Y1094260D01*
G01D02*
X7358D01*
G01X37396Y1130912D02*
X41916D01*
G01X43950Y1093500D02*
X22300D01*
G01D02*
X18390Y1097410D01*
G01D02*
X7358D01*
G01X67000Y1112000D02*
X36425Y1142575D01*
G01D02*
Y1231012D01*
G01X38600Y1233400D02*
Y1153700D01*
G01D02*
X112700Y1079600D01*
G01X7358Y1229693D02*
X12794D01*
G01D02*
X14596Y1227891D01*
G01D02*
Y1227805D01*
G01D02*
X15739Y1226662D01*
G01D02*
X17662D01*
G01D02*
X29900Y1238900D01*
G01D02*
X45550D01*
G01X33201Y1230674D02*
X23362D01*
G01D02*
X18046Y1225358D01*
G01D02*
X15357D01*
G01D02*
X14171Y1226544D01*
G01D02*
X7358D01*
G01X36425Y1231012D02*
X32959Y1234478D01*
G01X36000Y1236000D02*
X38600Y1233400D01*
G01X7358Y1314733D02*
X14033D01*
G01D02*
X14700Y1315400D01*
G01D02*
X17262D01*
G01D02*
X22787Y1309875D01*
G01D02*
X26099D01*
G01D02*
X33624Y1317400D01*
G01D02*
X50100D01*
G01X7358Y1311583D02*
X13183D01*
G01D02*
X15200Y1313600D01*
G01D02*
X17400D01*
G01D02*
X22300Y1308700D01*
G01D02*
X28000D01*
G01D02*
X34125Y1314825D01*
G01D02*
X65525D01*
G01X7358Y1308434D02*
X16166D01*
G01D02*
X19479Y1305121D01*
G01D02*
X26500D01*
G01X51213Y1301782D02*
X33699D01*
G01X70901Y1458325D02*
X32500Y1419924D01*
G01D02*
Y1417600D01*
G01X66618Y1460194D02*
X25094Y1418670D01*
G01D02*
X7358D01*
G01X27000Y1417500D02*
X70000Y1460500D01*
G01X40132Y1522350D02*
X38382Y1524100D01*
G01D02*
X32100D01*
G01D02*
X28000Y1520000D01*
G01D02*
X22000D01*
G01D02*
X17819Y1524181D01*
G01D02*
X7358D01*
G01Y1584023D02*
X15023D01*
G01D02*
X16000Y1585000D01*
G01D02*
X17500D01*
G01D02*
X23225Y1579275D01*
G01D02*
X25848D01*
G01D02*
X27336Y1580763D01*
G01D02*
X46578D01*
G01X52951Y1575800D02*
X17800D01*
G01D02*
X15876Y1577724D01*
G01D02*
X7358D01*
G01Y1580874D02*
X14826D01*
G01D02*
X15800Y1579900D01*
G01D02*
X17600D01*
G01D02*
X20000Y1577500D01*
G01D02*
X27123D01*
G01D02*
X27598Y1577975D01*
G01D02*
X50926D01*
G01X28523Y1650311D02*
X33734Y1645100D01*
G01D02*
Y1592360D01*
G01D02*
X42919Y1583175D01*
G01X38000Y1715000D02*
X39500D01*
G01X49591Y1731012D02*
X24079Y1705500D01*
G01D02*
X23000D01*
G01D02*
X18059Y1700559D01*
G01D02*
X7358D01*
G01Y1706858D02*
X14658D01*
G01D02*
X15600Y1707800D01*
G01D02*
X17800D01*
G01D02*
X19500Y1709500D01*
G01D02*
X21720D01*
G01D02*
X47582Y1735362D01*
G01X35900Y1706000D02*
X44273D01*
G01X34224Y1709000D02*
X42093D01*
G01X42021Y1712597D02*
X34252D01*
G01D02*
X31742Y1710087D01*
G01D02*
Y1669180D01*
G01D02*
X28523Y1665961D01*
G01D02*
Y1650311D01*
G01X48561Y1733187D02*
X22874Y1707500D01*
G01D02*
X20800D01*
G01D02*
X18150Y1704850D01*
G01D02*
X16050D01*
G01D02*
X14908Y1703708D01*
G01D02*
X7358D01*
G01Y1782448D02*
X14052D01*
G01D02*
X14700Y1781800D01*
G01D02*
X18675D01*
G01D02*
X27400Y1790525D01*
G01D02*
X47440D01*
G01X46539Y1792700D02*
X27084D01*
G01D02*
X20509Y1786125D01*
G01D02*
X15527D01*
G01D02*
X15000Y1785598D01*
G01D02*
X7358D01*
G01X27084Y1797050D02*
X23034Y1793000D01*
G01D02*
X15603D01*
G01D02*
X14500Y1791897D01*
G01D02*
X7358D01*
G01Y1788748D02*
X14252D01*
G01D02*
X14700Y1788300D01*
G01D02*
X20509D01*
G01D02*
X27084Y1794875D01*
G01X48341Y1788350D02*
X28301D01*
G01D02*
X19250Y1779299D01*
G01D02*
X7358D01*
G01Y1798196D02*
X22979D01*
G01D02*
X26183Y1801400D01*
G01D02*
X42935D01*
G01X44737Y1797050D02*
X27084D01*
G01X7358Y1795047D02*
X22906D01*
G01D02*
X27084Y1799225D01*
G01D02*
X43836D01*
G01X27084Y1794875D02*
X45638D01*
G01X113800Y50000D02*
X111050Y47250D01*
G01D02*
X90150D01*
G01D02*
X87500Y49900D01*
G01D02*
X66800D01*
G01D02*
X57200Y59500D01*
G01D02*
Y198600D01*
G01X112075Y216223D02*
X96701Y231597D01*
G01D02*
Y257071D01*
G01D02*
X68775Y284997D01*
G01X70950Y285898D02*
X98876Y257972D01*
G01D02*
Y232498D01*
G01D02*
X114650Y216724D01*
G01X97400Y220200D02*
X103300D01*
G01D02*
X105750Y217750D01*
G01D02*
X109900Y213600D01*
G01D02*
Y204296D01*
G01D02*
X147396Y166800D01*
G01X114579Y196219D02*
X107611Y203187D01*
G01D02*
Y211470D01*
G01D02*
X101448Y217633D01*
G01D02*
X96306D01*
G01D02*
X94526Y219413D01*
G01D02*
Y255574D01*
G01D02*
X64400Y285700D01*
G01X57200Y198600D02*
X92331Y233731D01*
G01D02*
Y254692D01*
G01D02*
X62225Y284798D01*
G01X75300Y287700D02*
X103271Y259729D01*
G01D02*
Y234750D01*
G01D02*
X119000Y219021D01*
G01X116825Y217625D02*
X101051Y233399D01*
G01D02*
Y258873D01*
G01D02*
X73125Y286799D01*
G01X80300Y234465D02*
X88596D01*
G01D02*
X90100Y235969D01*
G01D02*
Y253300D01*
G01D02*
X73900Y269500D01*
G01X68775Y284997D02*
Y293791D01*
G01D02*
X66610Y295956D01*
G01X70950Y321605D02*
Y285898D01*
G01X64400Y285700D02*
Y324517D01*
G01X62225Y284798D02*
Y323168D01*
G01X39500Y359400D02*
X75300Y323600D01*
G01D02*
Y287700D01*
G01X73125Y286799D02*
Y322699D01*
G01X73900Y269500D02*
X60050Y283350D01*
G01D02*
Y322267D01*
G01X52066Y370649D02*
X62121Y380704D01*
G01D02*
X78675D01*
G01X39500Y773652D02*
Y359400D01*
G01X149401Y729175D02*
X86901D01*
G01D02*
X45632Y770444D01*
G01D02*
Y782418D01*
G01X148500Y727000D02*
X86000D01*
G01D02*
X43457Y769543D01*
G01D02*
Y781041D01*
G01X49500Y771000D02*
X89150Y731350D01*
G01D02*
X150302D01*
G01X80215Y777137D02*
Y787900D01*
G01X46321Y873675D02*
Y827414D01*
G01D02*
X80215Y793520D01*
G01D02*
Y787900D01*
G01X52800Y898300D02*
Y825700D01*
G01D02*
X73000Y805500D01*
G01D02*
X80100D01*
G01X141900D02*
X80100D01*
G01X45632Y782418D02*
X43387Y784663D01*
G01D02*
Y803500D01*
G01D02*
Y872711D01*
G01X43457Y781041D02*
X40087Y784411D01*
G01D02*
Y788400D01*
G01D02*
Y866913D01*
G01X41000Y908000D02*
X47500Y901500D01*
G01X74000Y928000D02*
Y919500D01*
G01D02*
X52800Y898300D01*
G01X53400Y1008976D02*
Y935500D01*
G01D02*
X64200Y924700D01*
G01D02*
X70200D01*
G01D02*
X71000Y925500D01*
G01X56000Y1007500D02*
Y967000D01*
G01D02*
Y937000D01*
G01D02*
X65500Y927500D01*
G01X58675Y1007099D02*
Y937825D01*
G01D02*
X67500Y929000D01*
G01D02*
X73000D01*
G01D02*
X74000Y928000D01*
G01X106100Y1030000D02*
X118200Y1017900D01*
G01X106100Y1057497D02*
Y1030000D01*
G01X41444Y1128308D02*
X122800Y1046952D01*
G01X48798Y1085500D02*
X71000Y1063298D01*
G01D02*
Y1047000D01*
G01D02*
X74300Y1043700D01*
G01D02*
Y1029876D01*
G01D02*
X53400Y1008976D01*
G01X42734Y1133170D02*
X128300Y1047604D01*
G01X41608Y1125065D02*
X120500Y1046173D01*
G01X74000Y1047500D02*
X76750Y1044750D01*
G01D02*
Y1025929D01*
G01D02*
X65537Y1014716D01*
G01D02*
X63216D01*
G01D02*
X56000Y1007500D01*
G01X75500Y1081870D02*
Y1053000D01*
G01D02*
X79000Y1049500D01*
G01D02*
Y1025103D01*
G01D02*
X65744Y1011847D01*
G01D02*
X63423D01*
G01D02*
X58675Y1007099D01*
G01X81689Y1049400D02*
X81175Y1049914D01*
G01D02*
Y1066404D01*
G01X41916Y1130912D02*
X125800Y1047028D01*
G01X39959Y1128308D02*
X41444D01*
G01X42286Y1085500D02*
X48798D01*
G01X40097Y1142513D02*
X45610Y1137000D01*
G01D02*
X51000D01*
G01D02*
X124500Y1063500D01*
G01X81175Y1066404D02*
Y1079271D01*
G01X132000Y1051241D02*
X71241Y1112000D01*
G01D02*
X67000D01*
G01X67090Y1070360D02*
X43950Y1093500D01*
G01X51944Y1232506D02*
X85300Y1199150D01*
G01D02*
Y1182000D01*
G01X45550Y1238900D02*
X51944Y1232506D01*
G01X79390Y1284587D02*
X72500Y1277697D01*
G01X50100Y1317400D02*
X58500D01*
G01D02*
X58900Y1317000D01*
G01X65525Y1314825D02*
X69900Y1319200D01*
G01D02*
Y1331100D01*
G01D02*
X65000Y1336000D01*
G01X57000Y1410931D02*
Y1344000D01*
G01D02*
X65000Y1336000D01*
G01X59500Y1410131D02*
Y1345000D01*
G01D02*
X66000Y1338500D01*
G01D02*
X73500D01*
G01D02*
X79390Y1332610D01*
G01D02*
Y1327082D01*
G01D02*
Y1284587D01*
G01X71000Y1335488D02*
X71012D01*
G01D02*
X74500Y1332000D01*
G01D02*
Y1316297D01*
G01D02*
X70350Y1312147D01*
G01D02*
X61578D01*
G01D02*
X51213Y1301782D01*
G01X84097Y1438028D02*
X57000Y1410931D01*
G01X86384Y1437015D02*
X59500Y1410131D01*
G01X80300Y1451000D02*
X80407Y1450893D01*
G01D02*
X81578D01*
G01D02*
X84097Y1448374D01*
G01D02*
Y1438028D01*
G01X94642Y1456100D02*
X85456D01*
G01D02*
X83231Y1458325D01*
G01D02*
X70901D01*
G01X94642Y1456100D02*
X100824D01*
G01D02*
X158875Y1398049D01*
G01X73000Y1455100D02*
X74996Y1453104D01*
G01D02*
X82547D01*
G01D02*
X86384Y1449267D01*
G01D02*
Y1437015D01*
G01X69365Y1474719D02*
X66618Y1471972D01*
G01D02*
Y1460194D01*
G01X70000Y1460500D02*
X99500D01*
G01D02*
X162500Y1397500D01*
G01X46845Y1514264D02*
X41977D01*
G01D02*
X40132Y1516109D01*
G01D02*
Y1522350D01*
G01X49555Y1583740D02*
X57862Y1592047D01*
G01D02*
Y1705162D01*
G01X46578Y1580763D02*
X49555Y1583740D01*
G01X55738Y1578587D02*
X52951Y1575800D01*
G01X64525Y1591016D02*
Y1587374D01*
G01D02*
X55738Y1578587D01*
G01X58777Y1585826D02*
X60037Y1587086D01*
G01D02*
Y1700537D01*
G01X50926Y1577975D02*
X58777Y1585826D01*
G01X39500Y1715000D02*
X45150Y1720650D01*
G01D02*
X53337Y1728837D01*
G01X57862Y1705162D02*
X72472Y1719772D01*
G01D02*
X83424D01*
G01D02*
X83427Y1719775D01*
G01D02*
X83479D01*
G01D02*
X86704Y1723000D01*
G01X100915D02*
X103877Y1720038D01*
G01D02*
X112363D01*
G01X60037Y1700537D02*
X66400Y1706900D01*
G01X44273Y1706000D02*
X60220Y1721947D01*
G01X42093Y1709000D02*
X45402Y1712309D01*
G01D02*
X57215Y1724122D01*
G01X55724Y1726300D02*
X42021Y1712597D01*
G01X53337Y1728837D02*
X80237D01*
G01D02*
X85504Y1734104D01*
G01D02*
X97876D01*
G01D02*
X100471Y1736699D01*
G01D02*
X139501D01*
G01X83600Y1736600D02*
X85500Y1738500D01*
G01D02*
X99196D01*
G01D02*
X99570Y1738874D01*
G01D02*
X140426D01*
G01X83600Y1736600D02*
X78012Y1731012D01*
G01D02*
X49591D01*
G01X47440Y1790525D02*
X58525Y1801610D01*
G01X86704Y1723000D02*
X100915D01*
G01X56350Y1802511D02*
X46539Y1792700D01*
G01X47582Y1735362D02*
X75462D01*
G01D02*
X82950Y1742850D01*
G01D02*
X97394D01*
G01D02*
X97768Y1743224D01*
G01D02*
X133824D01*
G01X60220Y1721947D02*
X82523D01*
G01D02*
X82526Y1721950D01*
G01D02*
X82578D01*
G01D02*
X85803Y1725175D01*
G01D02*
X98175D01*
G01D02*
X103174Y1730174D01*
G01D02*
X114726D01*
G01X59429Y1799438D02*
X48341Y1788350D01*
G01X57215Y1724122D02*
X81622D01*
G01D02*
X81625Y1724125D01*
G01D02*
X81677D01*
G01D02*
X84902Y1727350D01*
G01D02*
X97274D01*
G01D02*
X102273Y1732349D01*
G01D02*
X122227D01*
G01X124476Y1734524D02*
X101372D01*
G01D02*
X98748Y1731900D01*
G01D02*
X86376D01*
G01D02*
X80776Y1726300D01*
G01D02*
X55724D01*
G01X67000Y1738000D02*
X60000D01*
G01D02*
X55500Y1742500D01*
G01D02*
Y1763000D01*
G01X95900Y1801000D02*
X78700Y1783800D01*
G01D02*
X68500D01*
G01D02*
X55500Y1770800D01*
G01D02*
Y1763000D01*
G01X136654Y1741049D02*
X98669D01*
G01D02*
X98295Y1740675D01*
G01D02*
X83851D01*
G01D02*
X76363Y1733187D01*
G01D02*
X48561D01*
G01X58525Y1801610D02*
Y1860851D01*
G01D02*
X59798Y1862124D01*
G01D02*
X59799D01*
G01D02*
X59888Y1862213D01*
G01D02*
Y1878840D01*
G01X67800Y1855200D02*
X70038Y1852962D01*
G01D02*
X84205D01*
G01D02*
X95802Y1841365D01*
G01D02*
Y1834055D01*
G01D02*
X93625Y1831878D01*
G01D02*
Y1802200D01*
G01X57713Y1877939D02*
Y1863115D01*
G01D02*
X57624Y1863026D01*
G01D02*
X57623D01*
G01D02*
X56350Y1861753D01*
G01D02*
Y1802511D01*
G01X85000Y1817100D02*
Y1815000D01*
G01D02*
X74100Y1804100D01*
G01D02*
Y1796200D01*
G01X42935Y1801400D02*
X47487Y1805952D01*
G01D02*
Y1870474D01*
G01X53200Y1865800D02*
Y1876300D01*
G01Y1865800D02*
Y1864756D01*
G01D02*
X52000Y1863556D01*
G01D02*
Y1863555D01*
G01D02*
X51837Y1863392D01*
G01D02*
Y1805952D01*
G01D02*
X51838Y1805951D01*
G01D02*
Y1804151D01*
G01D02*
X44737Y1797050D01*
G01X43836Y1799225D02*
X49662Y1805051D01*
G01D02*
Y1868200D01*
G01X45638Y1794875D02*
X54175Y1803412D01*
G01D02*
Y1862654D01*
G01D02*
X55538Y1864017D01*
G01D02*
Y1877038D01*
G01X62063Y1879741D02*
Y1861312D01*
G01D02*
X60701Y1859950D01*
G01D02*
Y1800709D01*
G01D02*
X59430Y1799438D01*
G01D02*
X59429D01*
G01X98000Y1848800D02*
X97977Y1848777D01*
G01D02*
Y1833154D01*
G01D02*
X95900Y1831077D01*
G01D02*
Y1801000D01*
G01X70650Y1897792D02*
X78369D01*
G01D02*
X133577Y1953000D01*
G01X70650Y1897792D02*
X53772D01*
G01D02*
X46868Y1890888D01*
G01D02*
Y1887765D01*
G01X59888Y1878840D02*
X58525Y1880203D01*
G01D02*
Y1886825D01*
G01D02*
X59669Y1887969D01*
G01D02*
X81310D01*
G01D02*
X126941Y1933600D01*
G01X126265Y1936000D02*
X80409Y1890144D01*
G01D02*
X58744D01*
G01D02*
X56350Y1887750D01*
G01D02*
Y1879302D01*
G01D02*
X57713Y1877939D01*
G01X124856Y1940743D02*
X78994Y1894881D01*
G01D02*
X63579D01*
G01X47487Y1870474D02*
X45825Y1872136D01*
G01D02*
Y1878402D01*
G01D02*
X49495Y1882072D01*
G01D02*
Y1890391D01*
G01D02*
X53985Y1894881D01*
G01D02*
X63579D01*
G01X53200Y1876300D02*
X52000Y1877500D01*
G01X48000D02*
X50100Y1875400D01*
G01D02*
Y1872800D01*
G01X49662Y1868200D02*
X50100Y1868638D01*
G01D02*
Y1872800D01*
G01X55538Y1877038D02*
X54175Y1878401D01*
G01D02*
Y1888775D01*
G01D02*
X57719Y1892319D01*
G01D02*
X79508D01*
G01D02*
X125489Y1938300D01*
G01X60897Y1885848D02*
X60700Y1885651D01*
G01D02*
Y1881104D01*
G01D02*
X62063Y1879741D01*
G01X208019Y18500D02*
X161100D01*
G01D02*
X143600Y36000D01*
G01D02*
Y43300D01*
G01D02*
X136900Y50000D01*
G01D02*
X113800D01*
G01X783297Y168975D02*
X148297D01*
G01D02*
X112075Y205197D01*
G01X114650Y205698D02*
X149198Y171150D01*
G01D02*
X784198D01*
G01X147396Y166800D02*
X194300D01*
G01X114579Y137775D02*
Y196219D01*
G01X119000Y207500D02*
X151000Y175500D01*
G01D02*
X786000D01*
G01X785099Y173325D02*
X150099D01*
G01D02*
X116825Y206599D01*
G01X112075Y205197D02*
Y216223D01*
G01X114650Y216724D02*
Y205698D01*
G01X143600Y252100D02*
X170200D01*
G01D02*
X172900Y249400D01*
G01X119000Y219021D02*
Y207500D01*
G01X116825Y206599D02*
Y217625D01*
G01X157750Y544750D02*
X153500Y549000D01*
G01D02*
Y581692D01*
G01D02*
X143700Y591492D01*
G01D02*
Y624200D01*
G01D02*
X140900Y627000D01*
G01D02*
Y647800D01*
G01X150850Y574350D02*
Y580925D01*
G01D02*
X141525Y590250D01*
G01D02*
Y608050D01*
G01D02*
X133000Y616575D01*
G01D02*
Y642976D01*
G01X140900Y647800D02*
X164749Y671649D01*
G01D02*
Y713827D01*
G01X133000Y642976D02*
X162574Y672550D01*
G01D02*
Y712926D01*
G01X167136Y714516D02*
Y661064D01*
G01D02*
X173000Y655200D01*
G01X164749Y713827D02*
X149401Y729175D01*
G01X162574Y712926D02*
X148500Y727000D01*
G01X150302Y731350D02*
X167136Y714516D01*
G01X143800Y807400D02*
X141900Y805500D01*
G01X142066Y958234D02*
X153600Y946700D01*
G01D02*
X160600D01*
G01D02*
X161200Y946100D01*
G01X118200Y1017900D02*
Y982100D01*
G01D02*
X142066Y958234D01*
G01X122800Y1046952D02*
Y986700D01*
G01D02*
X155300Y954200D01*
G01D02*
X155900D01*
G01X161700Y950800D02*
Y957600D01*
G01D02*
X141250Y978050D01*
G01X128300Y1047604D02*
Y991000D01*
G01D02*
X141250Y978050D01*
G01X120500Y1046173D02*
Y984500D01*
G01D02*
X154500Y950500D01*
G01D02*
X156900D01*
G01D02*
X157200Y950800D01*
G01X198900Y965477D02*
X161523D01*
G01D02*
X132000Y995000D01*
G01X157000Y957500D02*
X148000Y966500D01*
G01X125800Y1047028D02*
Y988700D01*
G01D02*
X148000Y966500D01*
G01X124500Y1063500D02*
X169900D01*
G01D02*
X173000Y1060400D01*
G01X132000Y1042000D02*
Y1051241D01*
G01Y995000D02*
Y1042000D01*
G01X112700Y1079600D02*
X125300Y1067000D01*
G01D02*
X139300D01*
G01X162500Y1359500D02*
X158250Y1355250D01*
G01D02*
Y1348054D01*
G01D02*
X154709Y1344513D01*
G01X158875Y1398049D02*
Y1376100D01*
G01X162500Y1380500D02*
Y1359500D01*
G01Y1397500D02*
Y1380500D01*
G01X173100Y1466300D02*
X170648Y1468752D01*
G01D02*
X148095D01*
G01X144500Y1731700D02*
Y1720500D01*
G01D02*
X144400Y1720400D01*
G01X112363Y1720038D02*
X116425Y1724100D01*
G01X139501Y1736699D02*
X144500Y1731700D01*
G01X140426Y1738874D02*
X147300Y1732000D01*
G01D02*
Y1724600D01*
G01D02*
X147200Y1724500D01*
G01D02*
Y1724400D01*
G01X116425Y1724100D02*
X140300D01*
G01X151452Y1810000D02*
Y1760852D01*
G01D02*
X147200Y1756600D01*
G01X133824Y1743224D02*
X147200Y1756600D01*
G01X114726Y1730174D02*
X117400Y1727500D01*
G01D02*
X122000D01*
G01X137000D02*
X122000D01*
G01X122227Y1732349D02*
X124751Y1729825D01*
G01D02*
X140825D01*
G01X136500Y1733000D02*
X126000D01*
G01D02*
X124476Y1734524D01*
G01X157900Y1770500D02*
Y1762295D01*
G01D02*
X136654Y1741049D01*
G01X157898Y1780145D02*
Y1777954D01*
G01D02*
X157900Y1777952D01*
G01D02*
Y1770500D01*
G01X126941Y1933600D02*
X130800D01*
G01D02*
X141200Y1944000D01*
G01X140299Y1946175D02*
X130124Y1936000D01*
G01D02*
X126265D01*
G01X125489Y1938300D02*
X129348D01*
G01D02*
X139548Y1948500D01*
G01X173500Y1871700D02*
X169230Y1875970D01*
G01D02*
X113500D01*
G01X133577Y1953000D02*
X728189D01*
G01X141200Y1944000D02*
X724000D01*
G01X724901Y1946175D02*
X140299D01*
G01X726953Y1950700D02*
X138672D01*
G01D02*
X128715Y1940743D01*
G01D02*
X124856D01*
G01X139548Y1948500D02*
X725652D01*
G01X213244Y23725D02*
X208019Y18500D01*
G01X194300Y166800D02*
X196200Y164900D01*
G01D02*
X201500D01*
G01D02*
X203400Y166800D01*
G01D02*
X292445D01*
G01X208875Y957200D02*
Y960370D01*
G01D02*
X209968Y961463D01*
G01D02*
Y1056332D01*
G01D02*
X196000Y1070300D01*
G01X277150Y1753550D02*
X233200D01*
G01D02*
X224875Y1761875D01*
G01D02*
Y1768100D01*
G01X292445Y166800D02*
X292600Y166955D01*
G01X332500Y605000D02*
X302000D01*
G01D02*
X298438Y608562D01*
G01D02*
Y613255D01*
G01D02*
X293162Y618531D01*
G01D02*
Y641962D01*
G01D02*
X303000Y651800D01*
G01D02*
Y812000D01*
G01D02*
X327000Y836000D01*
G01D02*
Y846100D01*
G01D02*
X328750Y847850D01*
G01D02*
Y1157250D01*
G01D02*
X331500Y1160000D01*
G01Y1184800D02*
X329000Y1187300D01*
G01D02*
Y1195100D01*
G01D02*
X319100Y1205000D01*
G01D02*
Y1238100D01*
G01D02*
X325912Y1244912D01*
G01D02*
Y1353088D01*
G01D02*
X311500Y1367500D01*
G01Y1374500D02*
Y1377000D01*
G01D02*
X319500Y1385000D01*
G01D02*
Y1389000D01*
G01X311500Y1367500D02*
Y1374500D01*
G01X338275Y1745348D02*
X285352D01*
G01D02*
X277150Y1753550D01*
G01X390000Y820500D02*
X398000Y828500D01*
G01D02*
Y840000D01*
G01D02*
X402000Y844000D01*
G01X360100Y808080D02*
X377580D01*
G01D02*
X390000Y820500D01*
G01X331500Y1160000D02*
Y1184800D01*
G01X383140Y1179640D02*
X359175D01*
G01X398750Y1188250D02*
X390140Y1179640D01*
G01D02*
X383140D01*
G01X395500Y1703000D02*
Y1690500D01*
G01X379000Y1726000D02*
X395500Y1709500D01*
G01D02*
Y1703000D01*
G01X376890Y1678000D02*
X383000D01*
G01D02*
X395500Y1690500D01*
G01X343668Y1750741D02*
X338275Y1745348D01*
G01X728189Y1953000D02*
X871825Y1809364D01*
G01X724000Y1944000D02*
X862500Y1805500D01*
G01X864675Y1806401D02*
X724901Y1946175D01*
G01X869325Y1808328D02*
X726953Y1950700D01*
G01X725652Y1948500D02*
X866850Y1807302D01*
G01X886100Y146700D02*
X805572D01*
G01D02*
X783297Y168975D01*
G01X784198Y171150D02*
X806473Y148875D01*
G01D02*
X864975D01*
G01X786000Y175500D02*
X807800Y153700D01*
G01D02*
X878200D01*
G01X879400Y151400D02*
X807024D01*
G01D02*
X785099Y173325D01*
G01X890500Y373500D02*
X812031D01*
G01D02*
X807756Y377775D01*
G01X928100Y188700D02*
X886100Y146700D01*
G01X878200Y153700D02*
X888000Y163500D01*
G01D02*
Y166500D01*
G01D02*
X890000Y168500D01*
G01D02*
X900000D01*
G01D02*
X925800Y194300D01*
G01X890469Y164804D02*
Y162469D01*
G01D02*
X879400Y151400D01*
G01X901600Y249800D02*
X923400D01*
G01X922300Y247200D02*
X906991D01*
G01D02*
X906691Y247500D01*
G01D02*
X900824D01*
G01D02*
X898300Y250024D01*
G01D02*
Y256400D01*
G01D02*
X907500Y265600D01*
G01D02*
Y356500D01*
G01D02*
X890500Y373500D01*
G01X871825Y1809364D02*
Y1788364D01*
G01D02*
X904089Y1756100D01*
G01D02*
X932589D01*
G01X862500Y1805500D02*
Y1784500D01*
G01D02*
X899900Y1747100D01*
G01D02*
X928400D01*
G01X929301Y1749275D02*
X900801D01*
G01D02*
X864675Y1785401D01*
G01D02*
Y1806401D01*
G01X931228Y1753925D02*
X902728D01*
G01D02*
X869325Y1787328D01*
G01D02*
Y1808328D01*
G01X866850Y1807302D02*
Y1786302D01*
G01D02*
X901702Y1751450D01*
G01D02*
X930202D01*
G01X928100Y245100D02*
Y188700D01*
G01X923400Y249800D02*
X928100Y245100D01*
G01X925800Y194300D02*
Y243700D01*
G01D02*
X922300Y247200D01*
G01X997500Y1638500D02*
X946000D01*
G01D02*
X936000Y1648500D01*
G01X973000Y1641500D02*
X985602D01*
G01X947325Y1741364D02*
Y1683825D01*
G01D02*
X938500Y1675000D01*
G01D02*
Y1651000D01*
G01D02*
X940573Y1648927D01*
G01D02*
X996573D01*
G01X937000Y1738500D02*
Y1692000D01*
G01D02*
X930000Y1685000D01*
G01D02*
X926500Y1681500D01*
G01D02*
Y1660000D01*
G01X939500Y1698000D02*
Y1739076D01*
G01X934825Y1682285D02*
X939500Y1686960D01*
G01D02*
Y1698000D01*
G01X936000Y1648500D02*
Y1676000D01*
G01D02*
X944825Y1684825D01*
G01D02*
Y1740328D01*
G01X942350Y1739302D02*
Y1686350D01*
G01D02*
X931000Y1675000D01*
G01D02*
Y1671500D01*
G01D02*
Y1659000D01*
G01X941000Y1653000D02*
X942898Y1651102D01*
G01D02*
X1008244D01*
G01X932589Y1756100D02*
X947325Y1741364D01*
G01X928400Y1747100D02*
X937000Y1738500D01*
G01X939500Y1739076D02*
X929301Y1749275D01*
G01X944825Y1740328D02*
X931228Y1753925D01*
G01X930202Y1751450D02*
X942350Y1739302D01*
G01X996573Y1648927D02*
X999398Y1646102D01*
G01D02*
X1008244D01*
G01Y1636102D02*
X999898D01*
G01D02*
X997500Y1638500D01*
G01X985602Y1641500D02*
X986000Y1641102D01*
G01D02*
X1008244D01*
M02*
